#ISCELL
  mstr_misc dns *
  *
#ISCELL
  mstr_symbols design_note *
  *
#ISCELL
  mstr_symbols intel_corp_bpage *
  *
#ISCELL
  mstr_symbols p3v3_stby *
  page213_i1
#ISCELL
  mstr_symbols gnd *
  page213_i10
#ISCELL
  mstr_symbols gnd *
  page213_i100
#CELL
  mstr_discrete cap *
  page213_i101
#CELL
  mstr_discrete res *
  page213_i103
#CELL
  mstr_discrete res *
  page213_i104
#CELL
  dev_discrete cap_a *
  page213_i105
#CELL
  dev_discrete cap_a *
  page213_i11
#ISCELL
  mstr_symbols gnd *
  page213_i12
#CELL
  mstr_discrete res *
  page213_i13
#CELL
  mstr_discrete res *
  page213_i14
#CELL
  mstr_discrete res *
  page213_i15
#CELL
  mstr_discrete res *
  page213_i16
#CELL
  dev_discrete cap_a *
  page213_i17
#ISCELL
  mstr_symbols gnd *
  page213_i18
#ISCELL
  mstr_standard offpage *
  page213_i2
#ISCELL
  mstr_symbols gnd *
  page213_i21
#ISCELL
  mstr_symbols p3v3_stby *
  page213_i24
#CELL
  mstr_discrete res *
  page213_i25
#ISCELL
  mstr_symbols pvccio_cpu1 *
  page213_i26
#CELL
  mstr_discrete res *
  page213_i27
#ISCELL
  mstr_symbols pvccio_cpu1 *
  page213_i28
#ISCELL
  mstr_standard offpage *
  page213_i3
#CELL
  mstr_discrete res *
  page213_i30
#CELL
  mstr_discrete res *
  page213_i31
#CELL
  mstr_discrete res *
  page213_i32
#ISCELL
  mstr_standard offpage *
  page213_i34
#CELL
  dev_discrete cap_a *
  page213_i35
#ISCELL
  mstr_symbols gnd *
  page213_i36
#CELL
  mstr_discrete res *
  page213_i37
#ISCELL
  mstr_symbols gnd *
  page213_i44
#ISCELL
  mstr_symbols gnd *
  page213_i45
#CELL
  mstr_discrete res *
  page213_i46
#ISCELL
  mstr_symbols gnd *
  page213_i47
#ISCELL
  mstr_symbols gnd *
  page213_i49
#ISCELL
  mstr_standard offpage *
  page213_i5
#ISCELL
  mstr_standard offpage *
  page213_i50
#ISCELL
  mstr_standard offpage *
  page213_i51
#ISCELL
  mstr_standard offpage *
  page213_i52
#ISCELL
  mstr_standard offpage *
  page213_i53
#ISCELL
  mstr_standard offpage *
  page213_i54
#ISCELL
  mstr_standard offpage *
  page213_i55
#ISCELL
  mstr_standard offpage *
  page213_i57
#ISCELL
  mstr_standard offpage *
  page213_i58
#ISCELL
  mstr_standard offpage *
  page213_i61
#ISCELL
  mstr_standard offpage *
  page213_i62
#CELL
  mstr_discrete res *
  page213_i63
#CELL
  mstr_discrete cap *
  page213_i73
#ISCELL
  mstr_symbols gnd *
  page213_i74
#ISCELL
  mstr_standard offpage *
  page213_i8
#CELL
  mstr_discrete cap *
  page213_i83
#CELL
  mstr_discrete res *
  page213_i84
#ISCELL
  mstr_standard offpage *
  page213_i86
#ISCELL
  mstr_standard offpage *
  page213_i87
#CELL
  dev_discrete cap_a *
  page213_i9
#CELL
  mstr_discrete res *
  page213_i90
#CELL
  mstr_discrete res *
  page213_i91
#ISCELL
  mstr_symbols universal_power *
  page213_i92
#CELL
  mstr_controller pxe1110b *
  page213_i96
#CELL
  w_hdl sc22p50v2jn-4gp *
  page213_i98
#CELL
  mstr_discrete res *
  page213_i99
